# S9S_MB_2U (Grand Teton) — schematic netlist excerpt (pin names and nets, part order shuffled) for the footprints in the layout excerpt that follows; sources: Cadence DE-HDL packaged netlist, KiCad conversion of 03242023_DA0F0TMBIJ0_F0T_Motherboard_J_brd_V01_OCP.brd

R106  Q_RES  2K 1% CHIP  pkg 0402LF  page 206 : A = GND ; B = FM_PLD_CLKS_DEV_EN
C227  Q_CAP  10UF 6.3V 20% X6S  pkg C0402  page 77 : A = PVCCIN_CPU1 ; B = GND

(kicad_pcb
	(version 20260206)
	(generator "pcbnew")
	(generator_version "10.0")
	(general
		(thickness 1.6)
		(legacy_teardrops no)
	)
	(paper "A4")
	(title_block
		(title "03242023_DA0F0TMBIJ0_F0T_Motherboard_J_brd_V01_OCP.brd")
		(comment 1 "Grand Teton / footprints 2077-2078 of 6105")
	)
	(layers
		(0 "F.Cu" signal "TOP")
		(4 "In1.Cu" signal "GND")
		(6 "In2.Cu" signal "IN1")
		(8 "In3.Cu" signal "GND1")
		(10 "In4.Cu" signal "IN2")
		(12 "In5.Cu" signal "GND2")
		(14 "In6.Cu" signal "IN3")
		(16 "In7.Cu" signal "GND3")
		(18 "In8.Cu" signal "VCC")
		(20 "In9.Cu" signal "VCC1")
		(22 "In10.Cu" signal "GND4")
		(24 "In11.Cu" signal "IN4")
		(26 "In12.Cu" signal "GND5")
		(28 "In13.Cu" signal "IN5")
		(30 "In14.Cu" signal "GND6")
		(32 "In15.Cu" signal "IN6")
		(34 "In16.Cu" signal "GND7")
		(2 "B.Cu" signal "BOTTOM")
		(9 "F.Adhes" user "F.Adhesive")
		(11 "B.Adhes" user "B.Adhesive")
		(13 "F.Paste" user "Package Geometry/Pastemask Top")
		(15 "B.Paste" user "Package Geometry/Pastemask Bottom")
		(5 "F.SilkS" user "Ref Des/Silkscreen Top")
		(7 "B.SilkS" user "Ref Des/Silkscreen Bottom")
		(1 "F.Mask" user "Board Geometry/Soldermask Top")
		(3 "B.Mask" user "Board Geometry/Soldermask Bottom")
		(17 "Dwgs.User" user "User.Drawings")
		(19 "Cmts.User" user "User.Comments")
		(21 "Eco1.User" user "User.Eco1")
		(23 "Eco2.User" user "User.Eco2")
		(25 "Edge.Cuts" user "Board Geometry/Outline")
		(27 "Margin" user)
		(31 "F.CrtYd" user "Package Geometry/Place Bound Top")
		(29 "B.CrtYd" user "Package Geometry/Place Bound Bottom")
		(35 "F.Fab" user "Ref Des/Assembly Top")
		(33 "B.Fab" user "Ref Des/Assembly Bottom")
	)
	(footprint ""
		(layer "F.Cu")
		(at 106.342434 -247.715278 90)
		(property "Reference" "C227"
			(at 0 0 90)
			(layer "F.SilkS")
			(hide yes)
			(effects
				(font
					(size 1.27 1.27)
				)
			)
		)
		(property "Value" ""
			(at 0 0 90)
			(layer "F.Fab")
			(effects
				(font
					(size 1.27 1.27)
				)
			)
		)
		(duplicate_pad_numbers_are_jumpers no)
		(fp_line
			(start 0.7874 -0.4064)
			(end 0.7874 0.4064)
			(stroke
				(width 0.1524)
				(type default)
			)
			(layer "F.SilkS")
		)
		(fp_line
			(start -0.7874 -0.4064)
			(end 0.7874 -0.4064)
			(stroke
				(width 0.1524)
				(type default)
			)
			(layer "F.SilkS")
		)
		(fp_line
			(start 0.7874 0.4064)
			(end -0.7874 0.4064)
			(stroke
				(width 0.1524)
				(type default)
			)
			(layer "F.SilkS")
		)
		(fp_line
			(start -0.7874 0.4064)
			(end -0.7874 -0.4064)
			(stroke
				(width 0.1524)
				(type default)
			)
			(layer "F.SilkS")
		)
		(fp_line
			(start -0.12065 -0.305054)
			(end -0.12065 -0.2794)
			(stroke
				(width 0.1)
				(type default)
			)
			(layer "F.Fab")
		)
		(fp_line
			(start -0.67945 -0.305054)
			(end -0.12065 -0.305054)
			(stroke
				(width 0.1)
				(type default)
			)
			(layer "F.Fab")
		)
		(fp_line
			(start 0.67945 -0.3048)
			(end 0.67945 0.3048)
			(stroke
				(width 0.1)
				(type default)
			)
			(layer "F.Fab")
		)
		(fp_line
			(start 0.12065 -0.3048)
			(end 0.67945 -0.3048)
			(stroke
				(width 0.1)
				(type default)
			)
			(layer "F.Fab")
		)
		(fp_line
			(start 0.12065 -0.2794)
			(end 0.12065 -0.3048)
			(stroke
				(width 0.1)
				(type default)
			)
			(layer "F.Fab")
		)
		(fp_line
			(start -0.12065 -0.2794)
			(end 0.12065 -0.2794)
			(stroke
				(width 0.1)
				(type default)
			)
			(layer "F.Fab")
		)
		(fp_line
			(start 0.120396 0.2794)
			(end -0.12065 0.2794)
			(stroke
				(width 0.1)
				(type default)
			)
			(layer "F.Fab")
		)
		(fp_line
			(start -0.12065 0.2794)
			(end -0.12065 0.3048)
			(stroke
				(width 0.1)
				(type default)
			)
			(layer "F.Fab")
		)
		(fp_line
			(start 0.67945 0.3048)
			(end 0.120396 0.3048)
			(stroke
				(width 0.1)
				(type default)
			)
			(layer "F.Fab")
		)
		(fp_line
			(start 0.120396 0.3048)
			(end 0.120396 0.2794)
			(stroke
				(width 0.1)
				(type default)
			)
			(layer "F.Fab")
		)
		(fp_line
			(start -0.12065 0.3048)
			(end -0.67945 0.3048)
			(stroke
				(width 0.1)
				(type default)
			)
			(layer "F.Fab")
		)
		(fp_line
			(start -0.67945 0.3048)
			(end -0.67945 -0.305054)
			(stroke
				(width 0.1)
				(type default)
			)
			(layer "F.Fab")
		)
		(pad "1" smd circle
			(at -0.40005 0 90)
			(size 0 0)
			(layers "F.Cu" "F.Mask" "F.Paste")
			(net "PVCCIN_CPU1")
		)
		(pad "2" smd circle
			(at 0.40005 0 90)
			(size 0 0)
			(layers "F.Cu" "F.Mask" "F.Paste")
			(net "GND")
		)
	)
	(footprint ""
		(layer "F.Cu")
		(at 250.890278 -92.36964)
		(property "Reference" "R106"
			(at 0 0 0)
			(layer "F.SilkS")
			(hide yes)
			(effects
				(font
					(size 1.27 1.27)
				)
			)
		)
		(property "Value" ""
			(at 0 0 0)
			(layer "F.Fab")
			(effects
				(font
					(size 1.27 1.27)
				)
			)
		)
		(duplicate_pad_numbers_are_jumpers no)
		(fp_line
			(start -0.7874 -0.4064)
			(end 0.7874 -0.4064)
			(stroke
				(width 0.1524)
				(type default)
			)
			(layer "F.SilkS")
		)
		(fp_line
			(start -0.7874 0.4064)
			(end -0.7874 -0.4064)
			(stroke
				(width 0.1524)
				(type default)
			)
			(layer "F.SilkS")
		)
		(fp_line
			(start 0.7874 -0.4064)
			(end 0.7874 0.4064)
			(stroke
				(width 0.1524)
				(type default)
			)
			(layer "F.SilkS")
		)
		(fp_line
			(start 0.7874 0.4064)
			(end -0.7874 0.4064)
			(stroke
				(width 0.1524)
				(type default)
			)
			(layer "F.SilkS")
		)
		(fp_line
			(start -0.67945 -0.305054)
			(end -0.12065 -0.305054)
			(stroke
				(width 0.1)
				(type default)
			)
			(layer "F.Fab")
		)
		(fp_line
			(start -0.67945 0.3048)
			(end -0.67945 -0.305054)
			(stroke
				(width 0.1)
				(type default)
			)
			(layer "F.Fab")
		)
		(fp_line
			(start -0.12065 -0.305054)
			(end -0.12065 -0.2794)
			(stroke
				(width 0.1)
				(type default)
			)
			(layer "F.Fab")
		)
		(fp_line
			(start -0.12065 -0.2794)
			(end 0.12065 -0.2794)
			(stroke
				(width 0.1)
				(type default)
			)
			(layer "F.Fab")
		)
		(fp_line
			(start -0.12065 0.2794)
			(end -0.12065 0.3048)
			(stroke
				(width 0.1)
				(type default)
			)
			(layer "F.Fab")
		)
		(fp_line
			(start -0.12065 0.3048)
			(end -0.67945 0.3048)
			(stroke
				(width 0.1)
				(type default)
			)
			(layer "F.Fab")
		)
		(fp_line
			(start 0.120396 0.2794)
			(end -0.12065 0.2794)
			(stroke
				(width 0.1)
				(type default)
			)
			(layer "F.Fab")
		)
		(fp_line
			(start 0.120396 0.3048)
			(end 0.120396 0.2794)
			(stroke
				(width 0.1)
				(type default)
			)
			(layer "F.Fab")
		)
		(fp_line
			(start 0.12065 -0.3048)
			(end 0.67945 -0.3048)
			(stroke
				(width 0.1)
				(type default)
			)
			(layer "F.Fab")
		)
		(fp_line
			(start 0.12065 -0.2794)
			(end 0.12065 -0.3048)
			(stroke
				(width 0.1)
				(type default)
			)
			(layer "F.Fab")
		)
		(fp_line
			(start 0.67945 -0.3048)
			(end 0.67945 0.3048)
			(stroke
				(width 0.1)
				(type default)
			)
			(layer "F.Fab")
		)
		(fp_line
			(start 0.67945 0.3048)
			(end 0.120396 0.3048)
			(stroke
				(width 0.1)
				(type default)
			)
			(layer "F.Fab")
		)
		(pad "1" smd circle
			(at -0.40005 0)
			(size 0 0)
			(layers "F.Cu" "F.Mask" "F.Paste")
			(net "GND")
		)
		(pad "2" smd circle
			(at 0.40005 0)
			(size 0 0)
			(layers "F.Cu" "F.Mask" "F.Paste")
			(net "FM_PLD_CLKS_DEV_EN")
		)
	)
)
